(kicad_pcb
	(version 20260206)
	(generator "pcbnew")
	(generator_version "10.0")
	(general
		(thickness 1.6)
		(legacy_teardrops no)
	)
	(paper "A4")
	(title_block
		(title "baseboard — 13948-1b.1110WZS1818.brd")
		(comment 1 "Honey Badger (Wiwynn) / footprints 369-375 of 2523")
	)
	(layers
		(0 "F.Cu" signal "TOP")
		(4 "In1.Cu" signal "L2GND")
		(6 "In2.Cu" signal "L3")
		(8 "In3.Cu" signal "L4VCC")
		(10 "In4.Cu" signal "L5VCC")
		(12 "In5.Cu" signal "L6")
		(14 "In6.Cu" signal "L7GND")
		(2 "B.Cu" signal "BOTTOM")
		(9 "F.Adhes" user "F.Adhesive")
		(11 "B.Adhes" user "B.Adhesive")
		(13 "F.Paste" user "Package Geometry/Pastemask Top")
		(15 "B.Paste" user "Package Geometry/Pastemask Bottom")
		(5 "F.SilkS" user "Ref Des/Silkscreen Top")
		(7 "B.SilkS" user "Ref Des/Silkscreen Bottom")
		(1 "F.Mask" user "Board Geometry/Soldermask Top")
		(3 "B.Mask" user "Board Geometry/Soldermask Bottom")
		(17 "Dwgs.User" user "User.Drawings")
		(19 "Cmts.User" user "User.Comments")
		(21 "Eco1.User" user "User.Eco1")
		(23 "Eco2.User" user "User.Eco2")
		(25 "Edge.Cuts" user "Board Geometry/Outline")
		(27 "Margin" user)
		(31 "F.CrtYd" user "Package Geometry/Place Bound Top")
		(29 "B.CrtYd" user "Package Geometry/Place Bound Bottom")
		(35 "F.Fab" user "Ref Des/Assembly Top")
		(33 "B.Fab" user "Ref Des/Assembly Bottom")
	)
	(footprint ""
		(layer "F.Cu")
		(at 289.678872 -71.700136 90)
		(property "Reference" "C266"
			(at 0 0 90)
			(layer "F.SilkS")
			(hide yes)
			(effects
				(font
					(size 1.27 1.27)
				)
			)
		)
		(property "Value" "SC2200P50V2KX-2GP"
			(at 1.1811 -2.7051 90)
			(unlocked yes)
			(layer "F.Fab")
			(hide yes)
			(effects
				(font
					(size 1.016 1.016)
					(thickness 0.1524)
				)
			)
		)
		(property "Device Type" "C402H22"
			(at 1.1811 -4.2291 90)
			(unlocked yes)
			(layer "F.Fab")
			(hide yes)
			(effects
				(font
					(size 1.016 1.016)
					(thickness 0.1524)
				)
			)
		)
		(duplicate_pad_numbers_are_jumpers no)
		(fp_rect
			(start -0.4318 0.9525)
			(end 0.4318 -0.9525)
			(stroke
				(width 0)
				(type default)
			)
			(fill no)
			(layer "F.CrtYd")
		)
		(fp_rect
			(start -0.4318 0.9525)
			(end 0.4318 -0.9525)
			(stroke
				(width 0)
				(type default)
			)
			(fill no)
			(layer "F.Fab")
		)
		(pad "1" smd custom
			(at 0 -0.4445 90)
			(size 0.1524 0.1524)
			(layers "F.Cu" "F.Mask" "F.Paste")
			(net "VR_HSC_GATE_MSB")
			(options
				(clearance outline)
				(anchor circle)
			)
			(primitives
				(gr_poly
					(pts
						(arc
							(start 0.3048 -0.2032)
							(mid 0.275042 -0.275042)
							(end 0.2032 -0.3048)
						)
						(arc
							(start -0.2032 -0.3048)
							(mid -0.275042 -0.275042)
							(end -0.3048 -0.2032)
						)
						(arc
							(start -0.3048 0.2032)
							(mid -0.275042 0.275042)
							(end -0.2032 0.3048)
						)
						(arc
							(start 0.2032 0.3048)
							(mid 0.275042 0.275042)
							(end 0.3048 0.2032)
						)
					)
					(width 0)
					(fill yes)
				)
			)
		)
		(pad "2" smd custom
			(at 0 0.4445 90)
			(size 0.1524 0.1524)
			(layers "F.Cu" "F.Mask" "F.Paste")
			(net "GND")
			(options
				(clearance outline)
				(anchor circle)
			)
			(primitives
				(gr_poly
					(pts
						(arc
							(start 0.3048 -0.2032)
							(mid 0.275042 -0.275042)
							(end 0.2032 -0.3048)
						)
						(arc
							(start -0.2032 -0.3048)
							(mid -0.275042 -0.275042)
							(end -0.3048 -0.2032)
						)
						(arc
							(start -0.3048 0.2032)
							(mid -0.275042 0.275042)
							(end -0.2032 0.3048)
						)
						(arc
							(start 0.2032 0.3048)
							(mid 0.275042 0.275042)
							(end 0.3048 0.2032)
						)
					)
					(width 0)
					(fill yes)
				)
			)
		)
	)
	(footprint ""
		(layer "F.Cu")
		(at 281.051 -182.3974)
		(property "Reference" "TP143"
			(at 0 0 0)
			(layer "F.SilkS")
			(hide yes)
			(effects
				(font
					(size 1.27 1.27)
				)
			)
		)
		(property "Value" "TPAD28"
			(at 0.0127 -1.8034 0)
			(unlocked yes)
			(layer "F.Fab")
			(hide yes)
			(effects
				(font
					(size 1.016 1.016)
					(thickness 0.1524)
				)
			)
		)
		(property "Device Type" "TPAD28"
			(at 0.0127 -3.3274 0)
			(unlocked yes)
			(layer "F.Fab")
			(hide yes)
			(effects
				(font
					(size 1.016 1.016)
					(thickness 0.1524)
				)
			)
		)
		(duplicate_pad_numbers_are_jumpers no)
		(fp_poly
			(pts
				(arc
					(start 0.3556 0)
					(mid -0.3556 0)
					(end 0.3556 0)
				)
			)
			(stroke
				(width 0)
				(type default)
			)
			(fill no)
			(layer "F.CrtYd")
		)
		(fp_poly
			(pts
				(arc
					(start 0.6096 0)
					(mid -0.6096 0)
					(end 0.6096 0)
				)
			)
			(stroke
				(width 0)
				(type default)
			)
			(fill no)
			(layer "F.Fab")
		)
		(pad "1" smd circle
			(at 0 0)
			(size 0.7112 0.7112)
			(layers "F.Cu" "F.Mask" "F.Paste")
			(net "TP_BMC_GPIOR1")
		)
	)
	(footprint ""
		(layer "F.Cu")
		(at 15.944088 -206.884016 180)
		(property "Reference" "SU52"
			(at 0 0 180)
			(layer "F.SilkS")
			(hide yes)
			(effects
				(font
					(size 1.27 1.27)
				)
			)
		)
		(property "Value" "PCA9306DCTT-GP"
			(at 0 -11.6332 180)
			(unlocked yes)
			(layer "F.Fab")
			(hide yes)
			(effects
				(font
					(size 1.016 1.016)
					(thickness 0.1524)
				)
			)
		)
		(property "Device Type" "SSOIC8H52"
			(at 0 -13.1572 180)
			(unlocked yes)
			(layer "F.Fab")
			(hide yes)
			(effects
				(font
					(size 1.016 1.016)
					(thickness 0.1524)
				)
			)
		)
		(duplicate_pad_numbers_are_jumpers no)
		(fp_line
			(start 1.0668 0.5842)
			(end -1.524 0.5842)
			(stroke
				(width 0.1524)
				(type default)
			)
			(layer "F.SilkS")
		)
		(fp_line
			(start 1.0668 -0.5842)
			(end 1.0668 0.5842)
			(stroke
				(width 0.1524)
				(type default)
			)
			(layer "F.SilkS")
		)
		(fp_line
			(start -1.397 0)
			(end -1.7018 0.3048)
			(stroke
				(width 0.1524)
				(type default)
			)
			(layer "F.SilkS")
		)
		(fp_line
			(start -1.397 0)
			(end -1.7018 -0.3048)
			(stroke
				(width 0.1524)
				(type default)
			)
			(layer "F.SilkS")
		)
		(fp_line
			(start -1.524 0.5842)
			(end -1.524 2.286)
			(stroke
				(width 0.508)
				(type default)
			)
			(layer "F.SilkS")
		)
		(fp_line
			(start -1.7018 -0.5842)
			(end 1.0668 -0.5842)
			(stroke
				(width 0.1524)
				(type default)
			)
			(layer "F.SilkS")
		)
		(fp_line
			(start -1.7018 -0.5842)
			(end -1.7018 2.286)
			(stroke
				(width 0.1524)
				(type default)
			)
			(layer "F.SilkS")
		)
		(fp_poly
			(pts
				(xy -1.1684 -0.5842) (xy 1.0668 -0.5842) (xy 1.0668 0.5842) (xy -1.1684 0.5842)
			)
			(stroke
				(width 0)
				(type default)
			)
			(fill yes)
			(layer "F.SilkS")
		)
		(fp_poly
			(pts
				(xy -1.778 2.54) (xy 1.778 2.54) (xy 1.778 -2.54) (xy -1.778 -2.54)
			)
			(stroke
				(width 0)
				(type default)
			)
			(fill no)
			(layer "F.CrtYd")
		)
		(fp_poly
			(pts
				(xy -1.778 -2.54) (xy 1.778 -2.54) (xy 1.778 2.54) (xy -1.778 2.54)
			)
			(stroke
				(width 0)
				(type default)
			)
			(fill no)
			(layer "F.Fab")
		)
		(pad "1" smd rect
			(at -0.97536 1.6256 180)
			(size 0.3556 1.524)
			(layers "F.Cu" "F.Mask" "F.Paste")
			(net "GND")
		)
		(pad "2" smd rect
			(at -0.32512 1.6256 180)
			(size 0.3556 1.524)
			(layers "F.Cu" "F.Mask" "F.Paste")
			(net "P1V8_E")
		)
		(pad "3" smd rect
			(at 0.32512 1.6256 180)
			(size 0.3556 1.524)
			(layers "F.Cu" "F.Mask" "F.Paste")
			(net "BMC_IOEXP_SCL_10")
		)
		(pad "4" smd rect
			(at 0.97536 1.6256 180)
			(size 0.3556 1.524)
			(layers "F.Cu" "F.Mask" "F.Paste")
			(net "BMC_IOEXP_SDA_10")
		)
		(pad "5" smd rect
			(at 0.97536 -1.6256 180)
			(size 0.3556 1.524)
			(layers "F.Cu" "F.Mask" "F.Paste")
			(net "BMC_I2C_SDA_10")
		)
		(pad "6" smd rect
			(at 0.32512 -1.6256 180)
			(size 0.3556 1.524)
			(layers "F.Cu" "F.Mask" "F.Paste")
			(net "BMC_I2C_SCL_10")
		)
		(pad "7" smd rect
			(at -0.32512 -1.6256 180)
			(size 0.3556 1.524)
			(layers "F.Cu" "F.Mask" "F.Paste")
			(net "BMC_I2C10_EN")
		)
		(pad "8" smd rect
			(at -0.97536 -1.6256 180)
			(size 0.3556 1.524)
			(layers "F.Cu" "F.Mask" "F.Paste")
			(net "BMC_I2C10_EN")
		)
	)
	(footprint ""
		(layer "F.Cu")
		(at 304.546 -102.108 180)
		(property "Reference" "R160"
			(at 0 0 180)
			(layer "F.SilkS")
			(hide yes)
			(effects
				(font
					(size 1.27 1.27)
				)
			)
		)
		(property "Value" "4K7R2F-GP"
			(at 0.064008 -3.993896 180)
			(unlocked yes)
			(layer "F.Fab")
			(hide yes)
			(effects
				(font
					(size 1.016 1.016)
					(thickness 0.1524)
				)
			)
		)
		(property "Device Type" "R402H16"
			(at 0.064008 -5.517896 180)
			(unlocked yes)
			(layer "F.Fab")
			(hide yes)
			(effects
				(font
					(size 1.016 1.016)
					(thickness 0.1524)
				)
			)
		)
		(duplicate_pad_numbers_are_jumpers no)
		(fp_line
			(start 0.508 -0.9398)
			(end -0.508 -0.9398)
			(stroke
				(width 0.1524)
				(type default)
			)
			(layer "F.SilkS")
		)
		(fp_line
			(start -0.508 -0.9398)
			(end -0.508 0.9398)
			(stroke
				(width 0.1524)
				(type default)
			)
			(layer "F.SilkS")
		)
		(fp_rect
			(start -0.508 0.9398)
			(end 0.508 -0.9398)
			(stroke
				(width 0)
				(type default)
			)
			(fill no)
			(layer "F.CrtYd")
		)
		(fp_rect
			(start -0.508 0.9398)
			(end 0.508 -0.9398)
			(stroke
				(width 0)
				(type default)
			)
			(fill no)
			(layer "F.Fab")
		)
		(pad "1" smd custom
			(at 0 -0.4445 180)
			(size 0.1397 0.1397)
			(layers "F.Cu" "F.Mask" "F.Paste")
			(net "TEMP_2_A2")
			(options
				(clearance outline)
				(anchor circle)
			)
			(primitives
				(gr_poly
					(pts
						(arc
							(start -0.1778 -0.2794)
							(mid -0.249642 -0.249642)
							(end -0.2794 -0.1778)
						)
						(arc
							(start -0.2794 0.1778)
							(mid -0.249642 0.249642)
							(end -0.1778 0.2794)
						)
						(arc
							(start 0.1778 0.2794)
							(mid 0.249642 0.249642)
							(end 0.2794 0.1778)
						)
						(arc
							(start 0.2794 -0.1778)
							(mid 0.249642 -0.249642)
							(end 0.1778 -0.2794)
						)
					)
					(width 0)
					(fill yes)
				)
			)
		)
		(pad "2" smd custom
			(at 0 0.4445 180)
			(size 0.1397 0.1397)
			(layers "F.Cu" "F.Mask" "F.Paste")
			(net "GND")
			(options
				(clearance outline)
				(anchor circle)
			)
			(primitives
				(gr_poly
					(pts
						(arc
							(start -0.1778 -0.2794)
							(mid -0.249642 -0.249642)
							(end -0.2794 -0.1778)
						)
						(arc
							(start -0.2794 0.1778)
							(mid -0.249642 0.249642)
							(end -0.1778 0.2794)
						)
						(arc
							(start 0.1778 0.2794)
							(mid 0.249642 0.249642)
							(end 0.2794 0.1778)
						)
						(arc
							(start 0.2794 -0.1778)
							(mid 0.249642 -0.249642)
							(end 0.1778 -0.2794)
						)
					)
					(width 0)
					(fill yes)
				)
			)
		)
	)
	(footprint ""
		(layer "F.Cu")
		(at 98.806 -221.488 180)
		(property "Reference" "R640"
			(at 0 0 180)
			(layer "F.SilkS")
			(hide yes)
			(effects
				(font
					(size 1.27 1.27)
				)
			)
		)
		(property "Value" "4K7R2F-GP"
			(at 0.064008 -3.993896 180)
			(unlocked yes)
			(layer "F.Fab")
			(hide yes)
			(effects
				(font
					(size 1.016 1.016)
					(thickness 0.1524)
				)
			)
		)
		(property "Device Type" "R402H16"
			(at 0.064008 -5.517896 180)
			(unlocked yes)
			(layer "F.Fab")
			(hide yes)
			(effects
				(font
					(size 1.016 1.016)
					(thickness 0.1524)
				)
			)
		)
		(duplicate_pad_numbers_are_jumpers no)
		(fp_line
			(start 0.508 -0.9398)
			(end -0.508 -0.9398)
			(stroke
				(width 0.1524)
				(type default)
			)
			(layer "F.SilkS")
		)
		(fp_line
			(start -0.508 -0.9398)
			(end -0.508 0.9398)
			(stroke
				(width 0.1524)
				(type default)
			)
			(layer "F.SilkS")
		)
		(fp_rect
			(start -0.508 0.9398)
			(end 0.508 -0.9398)
			(stroke
				(width 0)
				(type default)
			)
			(fill no)
			(layer "F.CrtYd")
		)
		(fp_rect
			(start -0.508 0.9398)
			(end 0.508 -0.9398)
			(stroke
				(width 0)
				(type default)
			)
			(fill no)
			(layer "F.Fab")
		)
		(pad "1" smd custom
			(at 0 -0.4445 180)
			(size 0.1397 0.1397)
			(layers "F.Cu" "F.Mask" "F.Paste")
			(net "P3V3_STBY")
			(options
				(clearance outline)
				(anchor circle)
			)
			(primitives
				(gr_poly
					(pts
						(arc
							(start -0.1778 -0.2794)
							(mid -0.249642 -0.249642)
							(end -0.2794 -0.1778)
						)
						(arc
							(start -0.2794 0.1778)
							(mid -0.249642 0.249642)
							(end -0.1778 0.2794)
						)
						(arc
							(start 0.1778 0.2794)
							(mid 0.249642 0.249642)
							(end 0.2794 0.1778)
						)
						(arc
							(start 0.2794 -0.1778)
							(mid 0.249642 -0.249642)
							(end 0.1778 -0.2794)
						)
					)
					(width 0)
					(fill yes)
				)
			)
		)
		(pad "2" smd custom
			(at 0 0.4445 180)
			(size 0.1397 0.1397)
			(layers "F.Cu" "F.Mask" "F.Paste")
			(net "IO_EXP_HDD_FAULT_A0")
			(options
				(clearance outline)
				(anchor circle)
			)
			(primitives
				(gr_poly
					(pts
						(arc
							(start -0.1778 -0.2794)
							(mid -0.249642 -0.249642)
							(end -0.2794 -0.1778)
						)
						(arc
							(start -0.2794 0.1778)
							(mid -0.249642 0.249642)
							(end -0.1778 0.2794)
						)
						(arc
							(start 0.1778 0.2794)
							(mid 0.249642 0.249642)
							(end 0.2794 0.1778)
						)
						(arc
							(start 0.2794 -0.1778)
							(mid 0.249642 -0.249642)
							(end 0.1778 -0.2794)
						)
					)
					(width 0)
					(fill yes)
				)
			)
		)
	)
	(footprint ""
		(layer "F.Cu")
		(at 338.455 -13.335)
		(property "Reference" "SR707"
			(at 0 0 0)
			(layer "F.SilkS")
			(hide yes)
			(effects
				(font
					(size 1.27 1.27)
				)
			)
		)
		(property "Value" "150R2F-1-GP"
			(at 0.064008 -3.993896 0)
			(unlocked yes)
			(layer "F.Fab")
			(hide yes)
			(effects
				(font
					(size 1.016 1.016)
					(thickness 0.1524)
				)
			)
		)
		(property "Device Type" "R402H16"
			(at 0.064008 -5.517896 0)
			(unlocked yes)
			(layer "F.Fab")
			(hide yes)
			(effects
				(font
					(size 1.016 1.016)
					(thickness 0.1524)
				)
			)
		)
		(duplicate_pad_numbers_are_jumpers no)
		(fp_line
			(start -0.508 -0.9398)
			(end -0.508 0.9398)
			(stroke
				(width 0.1524)
				(type default)
			)
			(layer "F.SilkS")
		)
		(fp_line
			(start 0.508 -0.9398)
			(end -0.508 -0.9398)
			(stroke
				(width 0.1524)
				(type default)
			)
			(layer "F.SilkS")
		)
		(fp_rect
			(start -0.508 0.9398)
			(end 0.508 -0.9398)
			(stroke
				(width 0)
				(type default)
			)
			(fill no)
			(layer "F.CrtYd")
		)
		(fp_rect
			(start -0.508 0.9398)
			(end 0.508 -0.9398)
			(stroke
				(width 0)
				(type default)
			)
			(fill no)
			(layer "F.Fab")
		)
		(pad "1" smd custom
			(at 0 -0.4445)
			(size 0.1397 0.1397)
			(layers "F.Cu" "F.Mask" "F.Paste")
			(net "P3V3_STBY")
			(options
				(clearance outline)
				(anchor circle)
			)
			(primitives
				(gr_poly
					(pts
						(arc
							(start -0.1778 -0.2794)
							(mid -0.249642 -0.249642)
							(end -0.2794 -0.1778)
						)
						(arc
							(start -0.2794 0.1778)
							(mid -0.249642 0.249642)
							(end -0.1778 0.2794)
						)
						(arc
							(start 0.1778 0.2794)
							(mid 0.249642 0.249642)
							(end 0.2794 0.1778)
						)
						(arc
							(start 0.2794 -0.1778)
							(mid 0.249642 -0.249642)
							(end 0.1778 -0.2794)
						)
					)
					(width 0)
					(fill yes)
				)
			)
		)
		(pad "2" smd custom
			(at 0 0.4445)
			(size 0.1397 0.1397)
			(layers "F.Cu" "F.Mask" "F.Paste")
			(net "EXP_BMC_HB_LED_R")
			(options
				(clearance outline)
				(anchor circle)
			)
			(primitives
				(gr_poly
					(pts
						(arc
							(start -0.1778 -0.2794)
							(mid -0.249642 -0.249642)
							(end -0.2794 -0.1778)
						)
						(arc
							(start -0.2794 0.1778)
							(mid -0.249642 0.249642)
							(end -0.1778 0.2794)
						)
						(arc
							(start 0.1778 0.2794)
							(mid 0.249642 0.249642)
							(end 0.2794 0.1778)
						)
						(arc
							(start 0.2794 -0.1778)
							(mid 0.249642 -0.249642)
							(end 0.1778 -0.2794)
						)
					)
					(width 0)
					(fill yes)
				)
			)
		)
	)
	(footprint ""
		(layer "F.Cu")
		(at 89.662 -223.139 -90)
		(property "Reference" "SR311"
			(at 0 0 270)
			(layer "F.SilkS")
			(hide yes)
			(effects
				(font
					(size 1.27 1.27)
				)
			)
		)
		(property "Value" "0R2J-2-GP"
			(at 0.064008 -3.993896 270)
			(unlocked yes)
			(layer "F.Fab")
			(hide yes)
			(effects
				(font
					(size 1.016 1.016)
					(thickness 0.1524)
				)
			)
		)
		(property "Device Type" "R402H16"
			(at 0.064008 -5.517896 270)
			(unlocked yes)
			(layer "F.Fab")
			(hide yes)
			(effects
				(font
					(size 1.016 1.016)
					(thickness 0.1524)
				)
			)
		)
		(duplicate_pad_numbers_are_jumpers no)
		(fp_line
			(start -0.508 -0.9398)
			(end -0.508 0.9398)
			(stroke
				(width 0.1524)
				(type default)
			)
			(layer "F.SilkS")
		)
		(fp_line
			(start 0.508 -0.9398)
			(end -0.508 -0.9398)
			(stroke
				(width 0.1524)
				(type default)
			)
			(layer "F.SilkS")
		)
		(fp_rect
			(start -0.508 0.9398)
			(end 0.508 -0.9398)
			(stroke
				(width 0)
				(type default)
			)
			(fill no)
			(layer "F.CrtYd")
		)
		(fp_rect
			(start -0.508 0.9398)
			(end 0.508 -0.9398)
			(stroke
				(width 0)
				(type default)
			)
			(fill no)
			(layer "F.Fab")
		)
		(pad "1" smd custom
			(at 0 -0.4445 270)
			(size 0.1397 0.1397)
			(layers "F.Cu" "F.Mask" "F.Paste")
			(net "FAULT_SDA")
			(options
				(clearance outline)
				(anchor circle)
			)
			(primitives
				(gr_poly
					(pts
						(arc
							(start -0.1778 -0.2794)
							(mid -0.249642 -0.249642)
							(end -0.2794 -0.1778)
						)
						(arc
							(start -0.2794 0.1778)
							(mid -0.249642 0.249642)
							(end -0.1778 0.2794)
						)
						(arc
							(start 0.1778 0.2794)
							(mid 0.249642 0.249642)
							(end 0.2794 0.1778)
						)
						(arc
							(start 0.2794 -0.1778)
							(mid 0.249642 -0.249642)
							(end 0.1778 -0.2794)
						)
					)
					(width 0)
					(fill yes)
				)
			)
		)
		(pad "2" smd custom
			(at 0 0.4445 270)
			(size 0.1397 0.1397)
			(layers "F.Cu" "F.Mask" "F.Paste")
			(net "EXP_SDA_L_0")
			(options
				(clearance outline)
				(anchor circle)
			)
			(primitives
				(gr_poly
					(pts
						(arc
							(start -0.1778 -0.2794)
							(mid -0.249642 -0.249642)
							(end -0.2794 -0.1778)
						)
						(arc
							(start -0.2794 0.1778)
							(mid -0.249642 0.249642)
							(end -0.1778 0.2794)
						)
						(arc
							(start 0.1778 0.2794)
							(mid 0.249642 0.249642)
							(end 0.2794 0.1778)
						)
						(arc
							(start 0.2794 -0.1778)
							(mid 0.249642 -0.249642)
							(end 0.1778 -0.2794)
						)
					)
					(width 0)
					(fill yes)
				)
			)
		)
	)
)
